(kicad_pcb
	(version 20260206)
	(generator "pcbnew")
	(generator_version "10.0")
	(general
		(thickness 1.6)
		(legacy_teardrops no)
	)
	(paper "A4")
	(title_block
		(title "04192023_DAF0TMB3IC0_F0TG_MB_C_brd_V02_OCP.brd")
		(comment 1 "Grand Teton / footprints 2076-2082 of 8354")
	)
	(layers
		(0 "F.Cu" signal "TOP")
		(4 "In1.Cu" signal "GND")
		(6 "In2.Cu" signal "IN1")
		(8 "In3.Cu" signal "GND1")
		(10 "In4.Cu" signal "IN2")
		(12 "In5.Cu" signal "GND2")
		(14 "In6.Cu" signal "IN3")
		(16 "In7.Cu" signal "GND3")
		(18 "In8.Cu" signal "VCC")
		(20 "In9.Cu" signal "VCC1")
		(22 "In10.Cu" signal "GND4")
		(24 "In11.Cu" signal "IN4")
		(26 "In12.Cu" signal "GND5")
		(28 "In13.Cu" signal "IN5")
		(30 "In14.Cu" signal "GND6")
		(32 "In15.Cu" signal "IN6")
		(34 "In16.Cu" signal "GND7")
		(2 "B.Cu" signal "BOTTOM")
		(9 "F.Adhes" user "F.Adhesive")
		(11 "B.Adhes" user "B.Adhesive")
		(13 "F.Paste" user "Package Geometry/Pastemask Top")
		(15 "B.Paste" user "Package Geometry/Pastemask Bottom")
		(5 "F.SilkS" user "Ref Des/Silkscreen Top")
		(7 "B.SilkS" user "Ref Des/Silkscreen Bottom")
		(1 "F.Mask" user "Board Geometry/Soldermask Top")
		(3 "B.Mask" user "Board Geometry/Soldermask Bottom")
		(17 "Dwgs.User" user "User.Drawings")
		(19 "Cmts.User" user "User.Comments")
		(21 "Eco1.User" user "User.Eco1")
		(23 "Eco2.User" user "User.Eco2")
		(25 "Edge.Cuts" user "Board Geometry/Outline")
		(27 "Margin" user)
		(31 "F.CrtYd" user "Package Geometry/Place Bound Top")
		(29 "B.CrtYd" user "Package Geometry/Place Bound Bottom")
		(35 "F.Fab" user "Ref Des/Assembly Top")
		(33 "B.Fab" user "Ref Des/Assembly Bottom")
	)
	(footprint ""
		(layer "F.Cu")
		(at 61.543438 -31.887922 90)
		(property "Reference" "R3874"
			(at 0 0 90)
			(layer "F.SilkS")
			(hide yes)
			(effects
				(font
					(size 1.27 1.27)
				)
			)
		)
		(property "Value" ""
			(at 0 0 90)
			(layer "F.Fab")
			(effects
				(font
					(size 1.27 1.27)
				)
			)
		)
		(duplicate_pad_numbers_are_jumpers no)
		(fp_line
			(start 0.7874 -0.4064)
			(end 0.7874 0.4064)
			(stroke
				(width 0.1524)
				(type default)
			)
			(layer "F.SilkS")
		)
		(fp_line
			(start -0.7874 -0.4064)
			(end 0.7874 -0.4064)
			(stroke
				(width 0.1524)
				(type default)
			)
			(layer "F.SilkS")
		)
		(fp_line
			(start 0.7874 0.4064)
			(end -0.7874 0.4064)
			(stroke
				(width 0.1524)
				(type default)
			)
			(layer "F.SilkS")
		)
		(fp_line
			(start -0.7874 0.4064)
			(end -0.7874 -0.4064)
			(stroke
				(width 0.1524)
				(type default)
			)
			(layer "F.SilkS")
		)
		(fp_line
			(start -0.12065 -0.305054)
			(end -0.12065 -0.2794)
			(stroke
				(width 0.1)
				(type default)
			)
			(layer "F.Fab")
		)
		(fp_line
			(start -0.67945 -0.305054)
			(end -0.12065 -0.305054)
			(stroke
				(width 0.1)
				(type default)
			)
			(layer "F.Fab")
		)
		(fp_line
			(start 0.67945 -0.3048)
			(end 0.67945 0.3048)
			(stroke
				(width 0.1)
				(type default)
			)
			(layer "F.Fab")
		)
		(fp_line
			(start 0.12065 -0.3048)
			(end 0.67945 -0.3048)
			(stroke
				(width 0.1)
				(type default)
			)
			(layer "F.Fab")
		)
		(fp_line
			(start 0.12065 -0.2794)
			(end 0.12065 -0.3048)
			(stroke
				(width 0.1)
				(type default)
			)
			(layer "F.Fab")
		)
		(fp_line
			(start -0.12065 -0.2794)
			(end 0.12065 -0.2794)
			(stroke
				(width 0.1)
				(type default)
			)
			(layer "F.Fab")
		)
		(fp_line
			(start 0.120396 0.2794)
			(end -0.12065 0.2794)
			(stroke
				(width 0.1)
				(type default)
			)
			(layer "F.Fab")
		)
		(fp_line
			(start -0.12065 0.2794)
			(end -0.12065 0.3048)
			(stroke
				(width 0.1)
				(type default)
			)
			(layer "F.Fab")
		)
		(fp_line
			(start 0.67945 0.3048)
			(end 0.120396 0.3048)
			(stroke
				(width 0.1)
				(type default)
			)
			(layer "F.Fab")
		)
		(fp_line
			(start 0.120396 0.3048)
			(end 0.120396 0.2794)
			(stroke
				(width 0.1)
				(type default)
			)
			(layer "F.Fab")
		)
		(fp_line
			(start -0.12065 0.3048)
			(end -0.67945 0.3048)
			(stroke
				(width 0.1)
				(type default)
			)
			(layer "F.Fab")
		)
		(fp_line
			(start -0.67945 0.3048)
			(end -0.67945 -0.305054)
			(stroke
				(width 0.1)
				(type default)
			)
			(layer "F.Fab")
		)
		(pad "1" smd circle
			(at -0.40005 0 90)
			(size 0 0)
			(layers "F.Cu" "F.Mask" "F.Paste")
			(net "P12V_OCP_IMON_2")
		)
		(pad "2" smd circle
			(at 0.40005 0 90)
			(size 0 0)
			(layers "F.Cu" "F.Mask" "F.Paste")
			(net "P12V_OCP_V3_2_ISENSE_MPS_TIC")
		)
	)
	(footprint ""
		(layer "F.Cu")
		(at 25.322784 -381.6858 -90)
		(property "Reference" "PL6512"
			(at 3.2258 -4.167886 90)
			(unlocked yes)
			(layer "F.SilkS")
			(effects
				(font
					(size 0.7874 0.5842)
					(thickness 0.1524)
				)
				(justify left)
			)
		)
		(property "Value" ""
			(at 0 0 270)
			(layer "F.Fab")
			(effects
				(font
					(size 1.27 1.27)
				)
			)
		)
		(duplicate_pad_numbers_are_jumpers no)
		(fp_line
			(start -3.24993 3.24993)
			(end -3.24993 2.2352)
			(stroke
				(width 0.1524)
				(type default)
			)
			(layer "F.SilkS")
		)
		(fp_line
			(start 3.24993 3.24993)
			(end -3.24993 3.24993)
			(stroke
				(width 0.1524)
				(type default)
			)
			(layer "F.SilkS")
		)
		(fp_line
			(start 3.24993 2.2352)
			(end 3.24993 3.24993)
			(stroke
				(width 0.1524)
				(type default)
			)
			(layer "F.SilkS")
		)
		(fp_line
			(start -3.24993 -2.2352)
			(end -3.24993 -3.24993)
			(stroke
				(width 0.1524)
				(type default)
			)
			(layer "F.SilkS")
		)
		(fp_line
			(start -3.24993 -3.24993)
			(end 3.24993 -3.24993)
			(stroke
				(width 0.1524)
				(type default)
			)
			(layer "F.SilkS")
		)
		(fp_line
			(start 3.24993 -3.24993)
			(end 3.24993 -2.2352)
			(stroke
				(width 0.1524)
				(type default)
			)
			(layer "F.SilkS")
		)
		(fp_line
			(start -3.24993 3.24993)
			(end -3.24993 -3.24993)
			(stroke
				(width 0.1)
				(type default)
			)
			(layer "F.Fab")
		)
		(fp_line
			(start 3.24993 3.24993)
			(end -3.24993 3.24993)
			(stroke
				(width 0.1)
				(type default)
			)
			(layer "F.Fab")
		)
		(fp_line
			(start -3.24993 -3.24993)
			(end 3.24993 -3.24993)
			(stroke
				(width 0.1)
				(type default)
			)
			(layer "F.Fab")
		)
		(fp_line
			(start 3.24993 -3.24993)
			(end 3.24993 3.24993)
			(stroke
				(width 0.1)
				(type default)
			)
			(layer "F.Fab")
		)
		(pad "1" smd rect
			(at -2.29997 0 270)
			(size 2.0066 4.2164)
			(layers "F.Cu" "F.Mask" "F.Paste")
			(net "SW_P0V9_RETIMER_CPU1_SW2")
		)
		(pad "2" smd rect
			(at 2.29997 0 270)
			(size 2.0066 4.2164)
			(layers "F.Cu" "F.Mask" "F.Paste")
			(net "P0V9_CPU1_RT_2D")
		)
	)
	(footprint ""
		(layer "F.Cu")
		(at 479.478594 -117.77472)
		(property "Reference" "DB2"
			(at 1.686814 3.227578 0)
			(unlocked yes)
			(layer "F.SilkS")
			(effects
				(font
					(size 0.7874 0.5842)
					(thickness 0.1524)
				)
				(justify left)
			)
		)
		(property "Value" ""
			(at 0 0 0)
			(layer "F.Fab")
			(effects
				(font
					(size 1.27 1.27)
				)
			)
		)
		(duplicate_pad_numbers_are_jumpers no)
		(fp_line
			(start -3.330702 -4.771136)
			(end 3.330702 -4.771136)
			(stroke
				(width 0.1524)
				(type default)
			)
			(layer "F.SilkS")
		)
		(fp_line
			(start 0 4.011168)
			(end -3.330702 -4.771136)
			(stroke
				(width 0.1524)
				(type default)
			)
			(layer "F.SilkS")
		)
		(fp_line
			(start 3.330702 -4.771136)
			(end 0 4.011168)
			(stroke
				(width 0.1524)
				(type default)
			)
			(layer "F.SilkS")
		)
		(fp_line
			(start -3.330702 -4.771136)
			(end 3.330702 -4.771136)
			(stroke
				(width 0.1)
				(type default)
			)
			(layer "F.Fab")
		)
		(fp_line
			(start 0 4.011168)
			(end -3.330702 -4.771136)
			(stroke
				(width 0.1)
				(type default)
			)
			(layer "F.Fab")
		)
		(fp_line
			(start 3.330702 -4.771136)
			(end 0 4.011168)
			(stroke
				(width 0.1)
				(type default)
			)
			(layer "F.Fab")
		)
		(pad "1" thru_hole circle
			(at 0 0)
			(size 2.159 2.159)
			(drill 1.7018)
			(layers "*.Cu" "*.Mask")
			(remove_unused_layers no)
			(net "T1_GND")
			(clearance 0.0254)
			(thermal_gap 0.0254)
		)
		(pad "2" thru_hole circle
			(at -1.27 -3.348736)
			(size 2.159 2.159)
			(drill 1.7018)
			(layers "*.Cu" "*.Mask")
			(remove_unused_layers no)
			(net "TDR_SE_45_OHM_IN1")
			(clearance 0.0254)
			(thermal_gap 0.0254)
		)
		(pad "3" thru_hole circle
			(at 1.27 -3.348736)
			(size 2.159 2.159)
			(drill 1.7018)
			(layers "*.Cu" "*.Mask")
			(remove_unused_layers no)
			(net "TDR_SE_45_OHM_IN1")
			(clearance 0.0254)
			(thermal_gap 0.0254)
		)
	)
	(footprint ""
		(layer "F.Cu")
		(at 130.638296 -151.8793 90)
		(property "Reference" "PC353"
			(at 0 0 90)
			(layer "F.SilkS")
			(hide yes)
			(effects
				(font
					(size 1.27 1.27)
				)
			)
		)
		(property "Value" ""
			(at 0 0 90)
			(layer "F.Fab")
			(effects
				(font
					(size 1.27 1.27)
				)
			)
		)
		(duplicate_pad_numbers_are_jumpers no)
		(fp_line
			(start 0.7874 -0.4064)
			(end 0.7874 0.4064)
			(stroke
				(width 0.1524)
				(type default)
			)
			(layer "F.SilkS")
		)
		(fp_line
			(start -0.7874 -0.4064)
			(end 0.7874 -0.4064)
			(stroke
				(width 0.1524)
				(type default)
			)
			(layer "F.SilkS")
		)
		(fp_line
			(start 0.7874 0.4064)
			(end -0.7874 0.4064)
			(stroke
				(width 0.1524)
				(type default)
			)
			(layer "F.SilkS")
		)
		(fp_line
			(start -0.7874 0.4064)
			(end -0.7874 -0.4064)
			(stroke
				(width 0.1524)
				(type default)
			)
			(layer "F.SilkS")
		)
		(fp_line
			(start -0.12065 -0.305054)
			(end -0.12065 -0.2794)
			(stroke
				(width 0.1)
				(type default)
			)
			(layer "F.Fab")
		)
		(fp_line
			(start -0.67945 -0.305054)
			(end -0.12065 -0.305054)
			(stroke
				(width 0.1)
				(type default)
			)
			(layer "F.Fab")
		)
		(fp_line
			(start 0.67945 -0.3048)
			(end 0.67945 0.3048)
			(stroke
				(width 0.1)
				(type default)
			)
			(layer "F.Fab")
		)
		(fp_line
			(start 0.12065 -0.3048)
			(end 0.67945 -0.3048)
			(stroke
				(width 0.1)
				(type default)
			)
			(layer "F.Fab")
		)
		(fp_line
			(start 0.12065 -0.2794)
			(end 0.12065 -0.3048)
			(stroke
				(width 0.1)
				(type default)
			)
			(layer "F.Fab")
		)
		(fp_line
			(start -0.12065 -0.2794)
			(end 0.12065 -0.2794)
			(stroke
				(width 0.1)
				(type default)
			)
			(layer "F.Fab")
		)
		(fp_line
			(start 0.120396 0.2794)
			(end -0.12065 0.2794)
			(stroke
				(width 0.1)
				(type default)
			)
			(layer "F.Fab")
		)
		(fp_line
			(start -0.12065 0.2794)
			(end -0.12065 0.3048)
			(stroke
				(width 0.1)
				(type default)
			)
			(layer "F.Fab")
		)
		(fp_line
			(start 0.67945 0.3048)
			(end 0.120396 0.3048)
			(stroke
				(width 0.1)
				(type default)
			)
			(layer "F.Fab")
		)
		(fp_line
			(start 0.120396 0.3048)
			(end 0.120396 0.2794)
			(stroke
				(width 0.1)
				(type default)
			)
			(layer "F.Fab")
		)
		(fp_line
			(start -0.12065 0.3048)
			(end -0.67945 0.3048)
			(stroke
				(width 0.1)
				(type default)
			)
			(layer "F.Fab")
		)
		(fp_line
			(start -0.67945 0.3048)
			(end -0.67945 -0.305054)
			(stroke
				(width 0.1)
				(type default)
			)
			(layer "F.Fab")
		)
		(pad "1" smd circle
			(at -0.40005 0 90)
			(size 0 0)
			(layers "F.Cu" "F.Mask" "F.Paste")
			(net "SW_PVDDCR_SOC_P1_BOOT3_RC")
		)
		(pad "2" smd circle
			(at 0.40005 0 90)
			(size 0 0)
			(layers "F.Cu" "F.Mask" "F.Paste")
			(net "SW_PVDDCR_SOC_P1_PH3")
		)
	)
	(footprint ""
		(layer "F.Cu")
		(at 221.361 -80.772 90)
		(property "Reference" "R8098"
			(at 0 0 90)
			(layer "F.SilkS")
			(hide yes)
			(effects
				(font
					(size 1.27 1.27)
				)
			)
		)
		(property "Value" ""
			(at 0 0 90)
			(layer "F.Fab")
			(effects
				(font
					(size 1.27 1.27)
				)
			)
		)
		(duplicate_pad_numbers_are_jumpers no)
		(fp_line
			(start 0.7874 -0.4064)
			(end 0.7874 0.4064)
			(stroke
				(width 0.1524)
				(type default)
			)
			(layer "F.SilkS")
		)
		(fp_line
			(start -0.7874 -0.4064)
			(end 0.7874 -0.4064)
			(stroke
				(width 0.1524)
				(type default)
			)
			(layer "F.SilkS")
		)
		(fp_line
			(start 0.7874 0.4064)
			(end -0.7874 0.4064)
			(stroke
				(width 0.1524)
				(type default)
			)
			(layer "F.SilkS")
		)
		(fp_line
			(start -0.7874 0.4064)
			(end -0.7874 -0.4064)
			(stroke
				(width 0.1524)
				(type default)
			)
			(layer "F.SilkS")
		)
		(fp_line
			(start -0.12065 -0.305054)
			(end -0.12065 -0.2794)
			(stroke
				(width 0.1)
				(type default)
			)
			(layer "F.Fab")
		)
		(fp_line
			(start -0.67945 -0.305054)
			(end -0.12065 -0.305054)
			(stroke
				(width 0.1)
				(type default)
			)
			(layer "F.Fab")
		)
		(fp_line
			(start 0.67945 -0.3048)
			(end 0.67945 0.3048)
			(stroke
				(width 0.1)
				(type default)
			)
			(layer "F.Fab")
		)
		(fp_line
			(start 0.12065 -0.3048)
			(end 0.67945 -0.3048)
			(stroke
				(width 0.1)
				(type default)
			)
			(layer "F.Fab")
		)
		(fp_line
			(start 0.12065 -0.2794)
			(end 0.12065 -0.3048)
			(stroke
				(width 0.1)
				(type default)
			)
			(layer "F.Fab")
		)
		(fp_line
			(start -0.12065 -0.2794)
			(end 0.12065 -0.2794)
			(stroke
				(width 0.1)
				(type default)
			)
			(layer "F.Fab")
		)
		(fp_line
			(start 0.120396 0.2794)
			(end -0.12065 0.2794)
			(stroke
				(width 0.1)
				(type default)
			)
			(layer "F.Fab")
		)
		(fp_line
			(start -0.12065 0.2794)
			(end -0.12065 0.3048)
			(stroke
				(width 0.1)
				(type default)
			)
			(layer "F.Fab")
		)
		(fp_line
			(start 0.67945 0.3048)
			(end 0.120396 0.3048)
			(stroke
				(width 0.1)
				(type default)
			)
			(layer "F.Fab")
		)
		(fp_line
			(start 0.120396 0.3048)
			(end 0.120396 0.2794)
			(stroke
				(width 0.1)
				(type default)
			)
			(layer "F.Fab")
		)
		(fp_line
			(start -0.12065 0.3048)
			(end -0.67945 0.3048)
			(stroke
				(width 0.1)
				(type default)
			)
			(layer "F.Fab")
		)
		(fp_line
			(start -0.67945 0.3048)
			(end -0.67945 -0.305054)
			(stroke
				(width 0.1)
				(type default)
			)
			(layer "F.Fab")
		)
		(pad "1" smd circle
			(at -0.40005 0 90)
			(size 0 0)
			(layers "F.Cu" "F.Mask" "F.Paste")
			(net "P3V3_E1S_0_R")
		)
		(pad "2" smd circle
			(at 0.40005 0 90)
			(size 0 0)
			(layers "F.Cu" "F.Mask" "F.Paste")
			(net "P3V3_E1S_PWRGD_0_R1")
		)
	)
	(footprint ""
		(layer "F.Cu")
		(at 79.114904 -396.491206 -90)
		(property "Reference" "R759"
			(at 0 0 270)
			(layer "F.SilkS")
			(hide yes)
			(effects
				(font
					(size 1.27 1.27)
				)
			)
		)
		(property "Value" ""
			(at 0 0 270)
			(layer "F.Fab")
			(effects
				(font
					(size 1.27 1.27)
				)
			)
		)
		(duplicate_pad_numbers_are_jumpers no)
		(fp_line
			(start -0.32512 0.175006)
			(end -0.32512 -0.175006)
			(stroke
				(width 0.1)
				(type default)
			)
			(layer "F.Fab")
		)
		(fp_line
			(start 0.32512 0.175006)
			(end -0.32512 0.175006)
			(stroke
				(width 0.1)
				(type default)
			)
			(layer "F.Fab")
		)
		(fp_line
			(start -0.32512 -0.175006)
			(end 0.32512 -0.175006)
			(stroke
				(width 0.1)
				(type default)
			)
			(layer "F.Fab")
		)
		(fp_line
			(start 0.32512 -0.175006)
			(end 0.32512 0.175006)
			(stroke
				(width 0.1)
				(type default)
			)
			(layer "F.Fab")
		)
		(pad "1" smd rect
			(at -0.2667 0 270)
			(size 0.3048 0.381)
			(layers "F.Cu" "F.Mask" "F.Paste")
			(net "P1V8_CPU1_RT_1D")
		)
		(pad "2" smd rect
			(at 0.2667 0 90)
			(size 0.3048 0.381)
			(layers "F.Cu" "F.Mask" "F.Paste")
			(net "JTAG_TEST_MODE_RT_CPU1_P1")
		)
	)
	(footprint ""
		(layer "F.Cu")
		(at 428.120302 -436.164736 90)
		(property "Reference" "R2833"
			(at 0 0 90)
			(layer "F.SilkS")
			(hide yes)
			(effects
				(font
					(size 1.27 1.27)
				)
			)
		)
		(property "Value" ""
			(at 0 0 90)
			(layer "F.Fab")
			(effects
				(font
					(size 1.27 1.27)
				)
			)
		)
		(duplicate_pad_numbers_are_jumpers no)
		(fp_line
			(start 0.7874 -0.4064)
			(end 0.7874 0.4064)
			(stroke
				(width 0.1524)
				(type default)
			)
			(layer "F.SilkS")
		)
		(fp_line
			(start -0.7874 -0.4064)
			(end 0.7874 -0.4064)
			(stroke
				(width 0.1524)
				(type default)
			)
			(layer "F.SilkS")
		)
		(fp_line
			(start 0.7874 0.4064)
			(end -0.7874 0.4064)
			(stroke
				(width 0.1524)
				(type default)
			)
			(layer "F.SilkS")
		)
		(fp_line
			(start -0.7874 0.4064)
			(end -0.7874 -0.4064)
			(stroke
				(width 0.1524)
				(type default)
			)
			(layer "F.SilkS")
		)
		(fp_line
			(start -0.12065 -0.305054)
			(end -0.12065 -0.2794)
			(stroke
				(width 0.1)
				(type default)
			)
			(layer "F.Fab")
		)
		(fp_line
			(start -0.67945 -0.305054)
			(end -0.12065 -0.305054)
			(stroke
				(width 0.1)
				(type default)
			)
			(layer "F.Fab")
		)
		(fp_line
			(start 0.67945 -0.3048)
			(end 0.67945 0.3048)
			(stroke
				(width 0.1)
				(type default)
			)
			(layer "F.Fab")
		)
		(fp_line
			(start 0.12065 -0.3048)
			(end 0.67945 -0.3048)
			(stroke
				(width 0.1)
				(type default)
			)
			(layer "F.Fab")
		)
		(fp_line
			(start 0.12065 -0.2794)
			(end 0.12065 -0.3048)
			(stroke
				(width 0.1)
				(type default)
			)
			(layer "F.Fab")
		)
		(fp_line
			(start -0.12065 -0.2794)
			(end 0.12065 -0.2794)
			(stroke
				(width 0.1)
				(type default)
			)
			(layer "F.Fab")
		)
		(fp_line
			(start 0.120396 0.2794)
			(end -0.12065 0.2794)
			(stroke
				(width 0.1)
				(type default)
			)
			(layer "F.Fab")
		)
		(fp_line
			(start -0.12065 0.2794)
			(end -0.12065 0.3048)
			(stroke
				(width 0.1)
				(type default)
			)
			(layer "F.Fab")
		)
		(fp_line
			(start 0.67945 0.3048)
			(end 0.120396 0.3048)
			(stroke
				(width 0.1)
				(type default)
			)
			(layer "F.Fab")
		)
		(fp_line
			(start 0.120396 0.3048)
			(end 0.120396 0.2794)
			(stroke
				(width 0.1)
				(type default)
			)
			(layer "F.Fab")
		)
		(fp_line
			(start -0.12065 0.3048)
			(end -0.67945 0.3048)
			(stroke
				(width 0.1)
				(type default)
			)
			(layer "F.Fab")
		)
		(fp_line
			(start -0.67945 0.3048)
			(end -0.67945 -0.305054)
			(stroke
				(width 0.1)
				(type default)
			)
			(layer "F.Fab")
		)
		(pad "1" smd circle
			(at -0.40005 0 90)
			(size 0 0)
			(layers "F.Cu" "F.Mask" "F.Paste")
			(net "FM_SWB_BIC_READY_N")
		)
		(pad "2" smd circle
			(at 0.40005 0 90)
			(size 0 0)
			(layers "F.Cu" "F.Mask" "F.Paste")
			(net "GND")
		)
	)
)
